(kicad_pcb
	(version 20260206)
	(generator "pcbnew")
	(generator_version "10.0")
	(general
		(thickness 1.6)
		(legacy_teardrops no)
	)
	(paper "A4")
	(title_block
		(title "Wiwynn_Tioga_Pass_MB.brd")
		(comment 1 "Tioga Pass / footprints 2983-2987 of 4770")
	)
	(layers
		(0 "F.Cu" signal "TOP")
		(4 "In1.Cu" signal "L2GND")
		(6 "In2.Cu" signal "L3")
		(8 "In3.Cu" signal "L4GND")
		(10 "In4.Cu" signal "L5")
		(12 "In5.Cu" signal "L6GND")
		(14 "In6.Cu" signal "L7VCC")
		(16 "In7.Cu" signal "L8VCC")
		(18 "In8.Cu" signal "L9GND")
		(20 "In9.Cu" signal "L10")
		(22 "In10.Cu" signal "L11GND")
		(24 "In11.Cu" signal "L12")
		(26 "In12.Cu" signal "L13GND")
		(2 "B.Cu" signal "BOTTOM")
		(9 "F.Adhes" user "F.Adhesive")
		(11 "B.Adhes" user "B.Adhesive")
		(13 "F.Paste" user "Package Geometry/Pastemask Top")
		(15 "B.Paste" user "Package Geometry/Pastemask Bottom")
		(5 "F.SilkS" user "Ref Des/Silkscreen Top")
		(7 "B.SilkS" user "Ref Des/Silkscreen Bottom")
		(1 "F.Mask" user "Board Geometry/Soldermask Top")
		(3 "B.Mask" user "Board Geometry/Soldermask Bottom")
		(17 "Dwgs.User" user "User.Drawings")
		(19 "Cmts.User" user "User.Comments")
		(21 "Eco1.User" user "User.Eco1")
		(23 "Eco2.User" user "User.Eco2")
		(25 "Edge.Cuts" user "Board Geometry/Outline")
		(27 "Margin" user)
		(31 "F.CrtYd" user "Package Geometry/Place Bound Top")
		(29 "B.CrtYd" user "Package Geometry/Place Bound Bottom")
		(35 "F.Fab" user "Ref Des/Assembly Top")
		(33 "B.Fab" user "Ref Des/Assembly Bottom")
	)
	(footprint ""
		(layer "B.Cu")
		(at 369.944904 -69.894196 180)
		(property "Reference" "C2R4"
			(at 0 0 0)
			(layer "B.SilkS")
			(hide yes)
			(effects
				(font
					(size 1.27 1.27)
				)
				(justify mirror)
			)
		)
		(property "Value" ""
			(at 0 0 0)
			(layer "B.Fab")
			(effects
				(font
					(size 1.27 1.27)
				)
				(justify mirror)
			)
		)
		(duplicate_pad_numbers_are_jumpers no)
		(fp_rect
			(start 0.2794 0.9144)
			(end -0.2794 -0.1143)
			(stroke
				(width 0)
				(type default)
			)
			(fill no)
			(layer "B.CrtYd")
		)
		(fp_line
			(start 0.2794 0.9144)
			(end 0.2794 -0.1143)
			(stroke
				(width 0.1)
				(type default)
			)
			(layer "B.Fab")
		)
		(fp_line
			(start 0.2794 -0.1143)
			(end -0.2794 -0.1143)
			(stroke
				(width 0.1)
				(type default)
			)
			(layer "B.Fab")
		)
		(fp_line
			(start -0.2794 0.9144)
			(end 0.2794 0.9144)
			(stroke
				(width 0.1)
				(type default)
			)
			(layer "B.Fab")
		)
		(fp_line
			(start -0.2794 -0.1143)
			(end -0.2794 0.9144)
			(stroke
				(width 0.1)
				(type default)
			)
			(layer "B.Fab")
		)
		(pad "1" smd custom
			(at 0 0 90)
			(size 0.10414 0.10414)
			(layers "B.Cu" "B.Mask" "B.Paste")
			(net "P3V3_STBY")
			(options
				(clearance outline)
				(anchor circle)
			)
			(primitives
				(gr_poly
					(pts
						(xy -0.20828 -0.08636) (xy -0.20828 0.08636) (xy -0.08636 0.20828) (xy 0.086614 0.20828) (xy 0.20828 0.086614)
						(xy 0.20828 -0.08636) (xy 0.08636 -0.20828) (xy -0.08636 -0.20828)
					)
					(width 0)
					(fill yes)
				)
			)
		)
		(pad "2" smd custom
			(at 0 0.8001 90)
			(size 0.10414 0.10414)
			(layers "B.Cu" "B.Mask" "B.Paste")
			(net "GND")
			(options
				(clearance outline)
				(anchor circle)
			)
			(primitives
				(gr_poly
					(pts
						(xy -0.20828 -0.08636) (xy -0.20828 0.08636) (xy -0.08636 0.20828) (xy 0.086614 0.20828) (xy 0.20828 0.086614)
						(xy 0.20828 -0.08636) (xy 0.08636 -0.20828) (xy -0.08636 -0.20828)
					)
					(width 0)
					(fill yes)
				)
			)
		)
		(zone
			(layer "B.Cu")
			(hatch none 0.5)
			(connect_pads
				(clearance 0)
			)
			(min_thickness 0.25)
			(keepout
				(tracks not_allowed)
				(vias allowed)
				(pads allowed)
				(copperpour not_allowed)
				(footprints allowed)
			)
			(placement
				(enabled no)
				(sheetname "")
			)
			(fill
				(thermal_gap 0.5)
				(thermal_bridge_width 0.5)
				(island_removal_mode 0)
			)
			(polygon
				(pts
					(xy 369.857274 -70.103746) (xy 369.857274 -70.484746) (xy 370.032534 -70.484746) (xy 370.032788 -70.103746)
				)
			)
		)
		(zone
			(layer "B.Cu")
			(hatch none 0.5)
			(connect_pads
				(clearance 0)
			)
			(min_thickness 0.25)
			(keepout
				(tracks allowed)
				(vias not_allowed)
				(pads allowed)
				(copperpour not_allowed)
				(footprints allowed)
			)
			(placement
				(enabled no)
				(sheetname "")
			)
			(fill
				(thermal_gap 0.5)
				(thermal_bridge_width 0.5)
				(island_removal_mode 0)
			)
			(polygon
				(pts
					(xy 369.857274 -70.103746) (xy 369.857274 -70.484746) (xy 370.032534 -70.484746) (xy 370.032788 -70.103746)
				)
			)
		)
	)
	(footprint ""
		(layer "B.Cu")
		(at 482.981 -114.554 90)
		(property "Reference" "C1M20"
			(at 0 0 90)
			(layer "B.SilkS")
			(hide yes)
			(effects
				(font
					(size 1.27 1.27)
				)
				(justify mirror)
			)
		)
		(property "Value" ""
			(at 0 0 90)
			(layer "B.Fab")
			(effects
				(font
					(size 1.27 1.27)
				)
				(justify mirror)
			)
		)
		(duplicate_pad_numbers_are_jumpers no)
		(fp_rect
			(start -0.3048 -0.1016)
			(end 0.3048 0.9906)
			(stroke
				(width 0)
				(type default)
			)
			(fill no)
			(layer "B.CrtYd")
		)
		(fp_line
			(start 0.3048 -0.1016)
			(end 0.3048 0.9906)
			(stroke
				(width 0.1)
				(type default)
			)
			(layer "B.Fab")
		)
		(fp_line
			(start -0.3048 -0.1016)
			(end 0.3048 -0.1016)
			(stroke
				(width 0.1)
				(type default)
			)
			(layer "B.Fab")
		)
		(fp_line
			(start 0.3048 0.9906)
			(end -0.3048 0.9906)
			(stroke
				(width 0.1)
				(type default)
			)
			(layer "B.Fab")
		)
		(fp_line
			(start -0.3048 0.9906)
			(end -0.3048 -0.1016)
			(stroke
				(width 0.1)
				(type default)
			)
			(layer "B.Fab")
		)
		(pad "1" smd rect
			(at 0 0 270)
			(size 0.508 0.508)
			(layers "B.Cu" "B.Mask" "B.Paste")
			(net "P3V3_STBY")
		)
		(pad "2" smd rect
			(at 0 0.889 270)
			(size 0.508 0.508)
			(layers "B.Cu" "B.Mask" "B.Paste")
			(net "GND")
		)
		(zone
			(layer "B.Cu")
			(hatch none 0.5)
			(connect_pads
				(clearance 0)
			)
			(min_thickness 0.25)
			(keepout
				(tracks allowed)
				(vias not_allowed)
				(pads allowed)
				(copperpour not_allowed)
				(footprints allowed)
			)
			(placement
				(enabled no)
				(sheetname "")
			)
			(fill
				(thermal_gap 0.5)
				(thermal_bridge_width 0.5)
				(island_removal_mode 0)
			)
			(polygon
				(pts
					(xy 483.235 -114.3) (xy 483.616 -114.3) (xy 483.616 -114.808) (xy 483.235 -114.808)
				)
			)
		)
		(zone
			(layer "B.Cu")
			(hatch none 0.5)
			(connect_pads
				(clearance 0)
			)
			(min_thickness 0.25)
			(keepout
				(tracks not_allowed)
				(vias allowed)
				(pads allowed)
				(copperpour not_allowed)
				(footprints allowed)
			)
			(placement
				(enabled no)
				(sheetname "")
			)
			(fill
				(thermal_gap 0.5)
				(thermal_bridge_width 0.5)
				(island_removal_mode 0)
			)
			(polygon
				(pts
					(xy 483.235 -114.3) (xy 483.616 -114.3) (xy 483.616 -114.808) (xy 483.235 -114.808)
				)
			)
		)
	)
	(footprint ""
		(layer "B.Cu")
		(at 111.605568 -27.305 90)
		(property "Reference" "C7T1"
			(at 0 0 90)
			(layer "B.SilkS")
			(hide yes)
			(effects
				(font
					(size 1.27 1.27)
				)
				(justify mirror)
			)
		)
		(property "Value" ""
			(at 0 0 90)
			(layer "B.Fab")
			(effects
				(font
					(size 1.27 1.27)
				)
				(justify mirror)
			)
		)
		(duplicate_pad_numbers_are_jumpers no)
		(fp_poly
			(pts
				(xy 0.7239 -0.2159) (xy -0.7239 -0.2159) (xy -0.7239 1.9939) (xy 0.7239 1.9939)
			)
			(stroke
				(width 0)
				(type default)
			)
			(fill no)
			(layer "B.CrtYd")
		)
		(fp_line
			(start 0.7239 -0.2159)
			(end 0.7239 1.9939)
			(stroke
				(width 0.1)
				(type default)
			)
			(layer "B.Fab")
		)
		(fp_line
			(start -0.7239 -0.2159)
			(end 0.7239 -0.2159)
			(stroke
				(width 0.1)
				(type default)
			)
			(layer "B.Fab")
		)
		(fp_line
			(start 0.7239 1.9939)
			(end -0.7239 1.9939)
			(stroke
				(width 0.1)
				(type default)
			)
			(layer "B.Fab")
		)
		(fp_line
			(start -0.7239 1.9939)
			(end -0.7239 -0.2159)
			(stroke
				(width 0.1)
				(type default)
			)
			(layer "B.Fab")
		)
		(pad "1" smd rect
			(at 0 0 270)
			(size 1.27 1.016)
			(layers "B.Cu" "B.Mask" "B.Paste")
			(net "PVDDQ_GHJ")
		)
		(pad "2" smd rect
			(at 0 1.778 270)
			(size 1.27 1.016)
			(layers "B.Cu" "B.Mask" "B.Paste")
			(net "GND")
		)
		(zone
			(layer "B.Cu")
			(hatch none 0.5)
			(connect_pads
				(clearance 0)
			)
			(min_thickness 0.25)
			(keepout
				(tracks not_allowed)
				(vias allowed)
				(pads allowed)
				(copperpour not_allowed)
				(footprints allowed)
			)
			(placement
				(enabled no)
				(sheetname "")
			)
			(fill
				(thermal_gap 0.5)
				(thermal_bridge_width 0.5)
				(island_removal_mode 0)
			)
			(polygon
				(pts
					(xy 112.113568 -27.94) (xy 112.113568 -26.67) (xy 112.875568 -26.67) (xy 112.875568 -27.94)
				)
			)
		)
	)
	(footprint ""
		(layer "B.Cu")
		(at 450.3674 -4.7498)
		(property "Reference" "R6W1"
			(at 0.8382 -0.67818 0)
			(unlocked yes)
			(layer "B.SilkS")
			(effects
				(font
					(size 0.4064 0.254)
					(thickness 0.1524)
				)
				(justify left mirror)
			)
		)
		(property "Value" ""
			(at 0 0 0)
			(layer "B.Fab")
			(effects
				(font
					(size 1.27 1.27)
				)
				(justify mirror)
			)
		)
		(duplicate_pad_numbers_are_jumpers no)
		(fp_poly
			(pts
				(xy 0.2794 -0.1016) (xy -0.2794 -0.1016) (xy -0.2794 0.9906) (xy 0.2794 0.9906)
			)
			(stroke
				(width 0)
				(type default)
			)
			(fill no)
			(layer "B.CrtYd")
		)
		(fp_line
			(start -0.2794 -0.1016)
			(end 0.2794 -0.1016)
			(stroke
				(width 0.1)
				(type default)
			)
			(layer "B.Fab")
		)
		(fp_line
			(start -0.2794 0.9906)
			(end -0.2794 -0.1016)
			(stroke
				(width 0.1)
				(type default)
			)
			(layer "B.Fab")
		)
		(fp_line
			(start 0.2794 -0.1016)
			(end 0.2794 0.9906)
			(stroke
				(width 0.1)
				(type default)
			)
			(layer "B.Fab")
		)
		(fp_line
			(start 0.2794 0.9906)
			(end -0.2794 0.9906)
			(stroke
				(width 0.1)
				(type default)
			)
			(layer "B.Fab")
		)
		(pad "1" smd rect
			(at 0 0 180)
			(size 0.508 0.508)
			(layers "B.Cu" "B.Mask" "B.Paste")
			(net "P3V3_STBY")
		)
		(pad "2" smd rect
			(at 0 0.889 180)
			(size 0.508 0.508)
			(layers "B.Cu" "B.Mask" "B.Paste")
			(net "PU_UV_HIGH_SET")
		)
		(zone
			(layer "B.Cu")
			(hatch none 0.5)
			(connect_pads
				(clearance 0)
			)
			(min_thickness 0.25)
			(keepout
				(tracks allowed)
				(vias not_allowed)
				(pads allowed)
				(copperpour not_allowed)
				(footprints allowed)
			)
			(placement
				(enabled no)
				(sheetname "")
			)
			(fill
				(thermal_gap 0.5)
				(thermal_bridge_width 0.5)
				(island_removal_mode 0)
			)
			(polygon
				(pts
					(xy 450.6214 -4.4958) (xy 450.1134 -4.4958) (xy 450.1134 -4.1148) (xy 450.6214 -4.1148)
				)
			)
		)
		(zone
			(layer "B.Cu")
			(hatch none 0.5)
			(connect_pads
				(clearance 0)
			)
			(min_thickness 0.25)
			(keepout
				(tracks not_allowed)
				(vias allowed)
				(pads allowed)
				(copperpour not_allowed)
				(footprints allowed)
			)
			(placement
				(enabled no)
				(sheetname "")
			)
			(fill
				(thermal_gap 0.5)
				(thermal_bridge_width 0.5)
				(island_removal_mode 0)
			)
			(polygon
				(pts
					(xy 450.6214 -4.1148) (xy 450.1134 -4.1148) (xy 450.1134 -4.4958) (xy 450.6214 -4.4958)
				)
			)
		)
	)
	(footprint ""
		(layer "B.Cu")
		(at 484.124 -150.0378 90)
		(property "Reference" "CR1L1"
			(at 0 0 90)
			(layer "B.SilkS")
			(hide yes)
			(effects
				(font
					(size 1.27 1.27)
				)
				(justify mirror)
			)
		)
		(property "Value" ""
			(at 0 0 90)
			(layer "B.Fab")
			(effects
				(font
					(size 1.27 1.27)
				)
				(justify mirror)
			)
		)
		(duplicate_pad_numbers_are_jumpers no)
		(fp_line
			(start 0.9144 0.1016)
			(end 0.9144 2.9464)
			(stroke
				(width 0.1524)
				(type default)
			)
			(layer "B.SilkS")
		)
		(fp_line
			(start 0.8382 0.1016)
			(end 0.9144 0.1016)
			(stroke
				(width 0.1524)
				(type default)
			)
			(layer "B.SilkS")
		)
		(fp_line
			(start -0.8382 0.1016)
			(end -0.9144 0.1016)
			(stroke
				(width 0.1524)
				(type default)
			)
			(layer "B.SilkS")
		)
		(fp_line
			(start -0.9144 0.1016)
			(end -0.9144 2.9464)
			(stroke
				(width 0.1524)
				(type default)
			)
			(layer "B.SilkS")
		)
		(fp_line
			(start 0.9144 2.9464)
			(end 0.8382 2.9464)
			(stroke
				(width 0.1524)
				(type default)
			)
			(layer "B.SilkS")
		)
		(fp_line
			(start -0.9144 2.9464)
			(end -0.8382 2.9464)
			(stroke
				(width 0.1524)
				(type default)
			)
			(layer "B.SilkS")
		)
		(fp_circle
			(center -1.128776 -0.907288)
			(end -1.128776 -0.780288)
			(stroke
				(width 0.254)
				(type default)
			)
			(fill no)
			(layer "B.SilkS")
		)
		(fp_poly
			(pts
				(xy 0 0.1016) (xy -0.5334 0.1016) (xy -0.7366 0.1016) (xy -0.9144 0.1016) (xy -0.9144 2.9464) (xy -0.8382 2.9464)
				(xy -0.762 2.9464) (xy 0.9144 2.9464) (xy 0.9144 2.7686) (xy 0.9144 2.159) (xy 0.9144 0.1016) (xy 0.7366 0.1016)
				(xy 0.5842 0.1016)
			)
			(stroke
				(width 0)
				(type default)
			)
			(fill no)
			(layer "B.CrtYd")
		)
		(fp_line
			(start 0.9144 0.1016)
			(end 0.9144 2.9464)
			(stroke
				(width 0.1)
				(type default)
			)
			(layer "B.Fab")
		)
		(fp_line
			(start -0.9144 0.1016)
			(end 0.9144 0.1016)
			(stroke
				(width 0.1)
				(type default)
			)
			(layer "B.Fab")
		)
		(fp_line
			(start 0.9144 2.9464)
			(end -0.9144 2.9464)
			(stroke
				(width 0.1)
				(type default)
			)
			(layer "B.Fab")
		)
		(fp_line
			(start -0.9144 2.9464)
			(end -0.9144 0.1016)
			(stroke
				(width 0.1)
				(type default)
			)
			(layer "B.Fab")
		)
		(fp_circle
			(center -1.128776 -0.907288)
			(end -1.128776 -0.780288)
			(stroke
				(width 0.254)
				(type default)
			)
			(fill no)
			(layer "B.Fab")
		)
		(pad "1" smd rect
			(at 0 0)
			(size 1.524 0.762)
			(layers "B.Cu" "B.Mask" "B.Paste")
			(net "FM_DB_UART_SEL1_N")
		)
		(pad "2" smd rect
			(at 0 3.048 180)
			(size 1.524 0.762)
			(layers "B.Cu" "B.Mask" "B.Paste")
			(net "FM_DB_UART_SEL0_N")
		)
	)
)
